# S9S_MB_2U (Grand Teton) — schematic netlist excerpt (pin names and nets, part order shuffled) for the footprints in the layout excerpt that follows; sources: Cadence DE-HDL packaged netlist, KiCad conversion of 03242023_DA0F0TMBIJ0_F0T_Motherboard_J_brd_V01_OCP.brd

J109  CONN112_10137002101LF  CONN112_10137002-101LF IO  pkg HSD_F112D8_P2W1-2_RDH  page 140
  A1  = BMC_MONITER_BUF
  A2  = GND
  A3  = BIC_MONITER
  A4  = GND
  A5  = SMB_BMC_SWB_BUF_SCL
  A6  = GND
  A7  = SMB_BMC_SWB_BUF_SDA
  A8  = GND
  B1  = GND
  B2  = P5E_CPU1_PE3_RX_DP<6>
  B3  = GND
  B4  = P5E_CPU1_PE3_RX_DP<4>
  B5  = GND
  B6  = P5E_CPU1_PE3_RX_DN<2>
  B7  = GND
  B8  = P5E_CPU1_PE3_RX_DP<0>
  C1  = P5E_CPU1_PE3_RX_DP<7>
  C2  = P5E_CPU1_PE3_RX_DN<6>
  C3  = P5E_CPU1_PE3_RX_DP<5>
  C4  = P5E_CPU1_PE3_RX_DN<4>
  C5  = P5E_CPU1_PE3_RX_DN<3>
  C6  = P5E_CPU1_PE3_RX_DP<2>
  C7  = P5E_CPU1_PE3_RX_DN<1>
  C8  = P5E_CPU1_PE3_RX_DN<0>
  D1  = P5E_CPU1_PE3_RX_DN<7>
  D2  = GND
  D3  = P5E_CPU1_PE3_RX_DN<5>
  D4  = GND
  D5  = P5E_CPU1_PE3_RX_DP<3>
  D6  = GND
  D7  = P5E_CPU1_PE3_RX_DP<1>
  D8  = GND
  E1  = GND
  E2  = P5E_CPU1_PE2_RX_DP<6>
  E3  = GND
  E4  = P5E_CPU1_PE2_RX_DP<4>
  E5  = GND
  E6  = P5E_CPU1_PE2_RX_DP<2>
  E7  = GND
  E8  = P5E_CPU1_PE2_RX_DP<0>
  F1  = P5E_CPU1_PE2_RX_DP<7>
  F2  = P5E_CPU1_PE2_RX_DN<6>
  F3  = P5E_CPU1_PE2_RX_DP<5>
  F4  = P5E_CPU1_PE2_RX_DN<4>
  F5  = P5E_CPU1_PE2_RX_DP<3>
  F6  = P5E_CPU1_PE2_RX_DN<2>
  F7  = P5E_CPU1_PE2_RX_DP<1>
  F8  = P5E_CPU1_PE2_RX_DN<0>
  G1  = P5E_CPU1_PE2_RX_DN<7>
  G2  = GND
  G3  = P5E_CPU1_PE2_RX_DN<5>
  G4  = GND
  G5  = P5E_CPU1_PE2_RX_DN<3>
  G6  = GND
  G7  = P5E_CPU1_PE2_RX_DN<1>
  G8  = GND
  H1  = GND
  H2  = P5E_CPU1_PE3_TX_C_DN<6>
  H3  = GND
  H4  = P5E_CPU1_PE3_TX_C_DN<4>
  H5  = GND
  H6  = P5E_CPU1_PE3_TX_C_DN<2>
  H7  = GND
  H8  = P5E_CPU1_PE3_TX_C_DP<0>
  I1  = P5E_CPU1_PE3_TX_C_DN<7>
  I2  = P5E_CPU1_PE3_TX_C_DP<6>
  I3  = P5E_CPU1_PE3_TX_C_DN<5>
  I4  = P5E_CPU1_PE3_TX_C_DP<4>
  I5  = P5E_CPU1_PE3_TX_C_DN<3>
  I6  = P5E_CPU1_PE3_TX_C_DP<2>
  I7  = P5E_CPU1_PE3_TX_C_DN<1>
  I8  = P5E_CPU1_PE3_TX_C_DN<0>
  J1  = P5E_CPU1_PE3_TX_C_DP<7>
  J2  = GND
  J3  = P5E_CPU1_PE3_TX_C_DP<5>
  J4  = GND
  J5  = P5E_CPU1_PE3_TX_C_DP<3>
  J6  = GND
  J7  = P5E_CPU1_PE3_TX_C_DP<1>
  J8  = GND
  K1  = GND
  K2  = P5E_CPU1_PE2_TX_C_DP<6>
  K3  = GND
  K4  = P5E_CPU1_PE2_TX_C_DP<4>
  K5  = GND
  K6  = P5E_CPU1_PE2_TX_C_DP<2>
  K7  = GND
  K8  = P5E_CPU1_PE2_TX_C_DP<0>
  L1  = P5E_CPU1_PE2_TX_C_DP<7>
  L2  = P5E_CPU1_PE2_TX_C_DN<6>
  L3  = P5E_CPU1_PE2_TX_C_DP<5>
  L4  = P5E_CPU1_PE2_TX_C_DN<4>
  L5  = P5E_CPU1_PE2_TX_C_DP<3>
  L6  = P5E_CPU1_PE2_TX_C_DN<2>
  L7  = P5E_CPU1_PE2_TX_C_DP<1>
  L8  = P5E_CPU1_PE2_TX_C_DN<0>
  M1  = P5E_CPU1_PE2_TX_C_DN<7>
  M2  = GND
  M3  = P5E_CPU1_PE2_TX_C_DN<5>
  M4  = GND
  M5  = P5E_CPU1_PE2_TX_C_DN<3>
  M6  = GND
  M7  = P5E_CPU1_PE2_TX_C_DN<1>
  M8  = GND
  N1  = GND
  N2  = GPU_FPGA_EROT_FATALERR_N
  N3  = GND
  N4  = GPU_3V3IO_RSVD0_FFU
  N5  = GND
  N6  = GPU_3V3IO_RSVD1_FFU
  N7  = GND
  N8  = PRSNT_CABLE_GPU_B3_N

(kicad_pcb
	(version 20260206)
	(generator "pcbnew")
	(generator_version "10.0")
	(general
		(thickness 1.6)
		(legacy_teardrops no)
	)
	(paper "A4")
	(title_block
		(title "03242023_DA0F0TMBIJ0_F0T_Motherboard_J_brd_V01_OCP.brd")
		(comment 1 "Grand Teton / footprint 3035 of 6105 (J109), pads 1-31 of 48")
	)
	(layers
		(0 "F.Cu" signal "TOP")
		(4 "In1.Cu" signal "GND")
		(6 "In2.Cu" signal "IN1")
		(8 "In3.Cu" signal "GND1")
		(10 "In4.Cu" signal "IN2")
		(12 "In5.Cu" signal "GND2")
		(14 "In6.Cu" signal "IN3")
		(16 "In7.Cu" signal "GND3")
		(18 "In8.Cu" signal "VCC")
		(20 "In9.Cu" signal "VCC1")
		(22 "In10.Cu" signal "GND4")
		(24 "In11.Cu" signal "IN4")
		(26 "In12.Cu" signal "GND5")
		(28 "In13.Cu" signal "IN5")
		(30 "In14.Cu" signal "GND6")
		(32 "In15.Cu" signal "IN6")
		(34 "In16.Cu" signal "GND7")
		(2 "B.Cu" signal "BOTTOM")
		(9 "F.Adhes" user "F.Adhesive")
		(11 "B.Adhes" user "B.Adhesive")
		(13 "F.Paste" user "Package Geometry/Pastemask Top")
		(15 "B.Paste" user "Package Geometry/Pastemask Bottom")
		(5 "F.SilkS" user "Ref Des/Silkscreen Top")
		(7 "B.SilkS" user "Ref Des/Silkscreen Bottom")
		(1 "F.Mask" user "Board Geometry/Soldermask Top")
		(3 "B.Mask" user "Board Geometry/Soldermask Bottom")
		(17 "Dwgs.User" user "User.Drawings")
		(19 "Cmts.User" user "User.Comments")
		(21 "Eco1.User" user "User.Eco1")
		(23 "Eco2.User" user "User.Eco2")
		(25 "Edge.Cuts" user "Board Geometry/Outline")
		(27 "Margin" user)
		(31 "F.CrtYd" user "Package Geometry/Place Bound Top")
		(29 "B.CrtYd" user "Package Geometry/Place Bound Bottom")
		(35 "F.Fab" user "Ref Des/Assembly Top")
		(33 "B.Fab" user "Ref Des/Assembly Bottom")
	)
	(footprint ""
		(layer "F.Cu")
		(at 142.750032 -440.489848)
		(property "Reference" "J109"
			(at 1.4859 23.131272 0)
			(unlocked yes)
			(layer "F.SilkS")
			(effects
				(font
					(size 0.7874 0.5842)
					(thickness 0.1524)
				)
				(justify left)
			)
		)
		(property "Value" ""
			(at 0 0 0)
			(layer "F.Fab")
			(effects
				(font
					(size 1.27 1.27)
				)
			)
		)
		(duplicate_pad_numbers_are_jumpers no)
		(pad "A1" thru_hole rect
			(at 0 0 180)
			(size 0.766318 0.766318)
			(drill 0.359918)
			(layers "*.Cu" "*.Mask")
			(remove_unused_layers no)
			(net "BMC_MONITER_BUF")
			(clearance 0.0508)
			(thermal_gap 0.0508)
			(padstack
				(mode front_inner_back)
				(layer "Inner"
					(shape circle)
					(size 0.766318 0.766318)
					(clearance 0.0508)
				)
				(layer "B.Cu"
					(shape rect)
					(size 0.766318 0.766318)
					(clearance 0.0508)
				)
			)
		)
		(pad "A2" thru_hole circle
			(at 1.999996 0.199898 180)
			(size 0.906272 0.906272)
			(drill 0.499872)
			(layers "*.Cu" "*.Mask")
			(remove_unused_layers no)
			(net "GND")
			(clearance 0.0508)
			(thermal_gap 0.0508)
		)
		(pad "A3" thru_hole circle
			(at 3.999992 0 180)
			(size 0.766318 0.766318)
			(drill 0.359918)
			(layers "*.Cu" "*.Mask")
			(remove_unused_layers no)
			(net "BIC_MONITER")
			(clearance 0.0508)
			(thermal_gap 0.0508)
		)
		(pad "A4" thru_hole circle
			(at 5.999988 0.199898 180)
			(size 0.906272 0.906272)
			(drill 0.499872)
			(layers "*.Cu" "*.Mask")
			(remove_unused_layers no)
			(net "GND")
			(clearance 0.0508)
			(thermal_gap 0.0508)
		)
		(pad "A5" thru_hole circle
			(at 7.999984 0 180)
			(size 0.766318 0.766318)
			(drill 0.359918)
			(layers "*.Cu" "*.Mask")
			(remove_unused_layers no)
			(net "SMB_BMC_SWB_BUF_SCL")
			(clearance 0.0508)
			(thermal_gap 0.0508)
		)
		(pad "A6" thru_hole circle
			(at 9.99998 0.199898 180)
			(size 0.906272 0.906272)
			(drill 0.499872)
			(layers "*.Cu" "*.Mask")
			(remove_unused_layers no)
			(net "GND")
			(clearance 0.0508)
			(thermal_gap 0.0508)
		)
		(pad "A7" thru_hole circle
			(at 11.999976 0 180)
			(size 0.766318 0.766318)
			(drill 0.359918)
			(layers "*.Cu" "*.Mask")
			(remove_unused_layers no)
			(net "SMB_BMC_SWB_BUF_SDA")
			(clearance 0.0508)
			(thermal_gap 0.0508)
		)
		(pad "A8" thru_hole circle
			(at 13.999972 0.199898 180)
			(size 0.906272 0.906272)
			(drill 0.499872)
			(layers "*.Cu" "*.Mask")
			(remove_unused_layers no)
			(net "GND")
			(clearance 0.0508)
			(thermal_gap 0.0508)
		)
		(pad "B1" thru_hole circle
			(at 0 1.199896 180)
			(size 0.906272 0.906272)
			(drill 0.499872)
			(layers "*.Cu" "*.Mask")
			(remove_unused_layers no)
			(net "GND")
			(clearance 0.0508)
			(thermal_gap 0.0508)
		)
		(pad "B3" thru_hole circle
			(at 3.999992 1.199896 180)
			(size 0.906272 0.906272)
			(drill 0.499872)
			(layers "*.Cu" "*.Mask")
			(remove_unused_layers no)
			(net "GND")
			(clearance 0.0508)
			(thermal_gap 0.0508)
		)
		(pad "B5" thru_hole circle
			(at 7.999984 1.199896 180)
			(size 0.906272 0.906272)
			(drill 0.499872)
			(layers "*.Cu" "*.Mask")
			(remove_unused_layers no)
			(net "GND")
			(clearance 0.0508)
			(thermal_gap 0.0508)
		)
		(pad "B7" thru_hole circle
			(at 11.999976 1.199896 180)
			(size 0.906272 0.906272)
			(drill 0.499872)
			(layers "*.Cu" "*.Mask")
			(remove_unused_layers no)
			(net "GND")
			(clearance 0.0508)
			(thermal_gap 0.0508)
		)
		(pad "D2" thru_hole circle
			(at 1.999996 3.800094 180)
			(size 0.906272 0.906272)
			(drill 0.499872)
			(layers "*.Cu" "*.Mask")
			(remove_unused_layers no)
			(net "GND")
			(clearance 0.0508)
			(thermal_gap 0.0508)
		)
		(pad "D4" thru_hole circle
			(at 5.999988 3.800094 180)
			(size 0.906272 0.906272)
			(drill 0.499872)
			(layers "*.Cu" "*.Mask")
			(remove_unused_layers no)
			(net "GND")
			(clearance 0.0508)
			(thermal_gap 0.0508)
		)
		(pad "D6" thru_hole circle
			(at 9.99998 3.800094 180)
			(size 0.906272 0.906272)
			(drill 0.499872)
			(layers "*.Cu" "*.Mask")
			(remove_unused_layers no)
			(net "GND")
			(clearance 0.0508)
			(thermal_gap 0.0508)
		)
		(pad "D8" thru_hole circle
			(at 13.999972 3.800094 180)
			(size 0.906272 0.906272)
			(drill 0.499872)
			(layers "*.Cu" "*.Mask")
			(remove_unused_layers no)
			(net "GND")
			(clearance 0.0508)
			(thermal_gap 0.0508)
		)
		(pad "E1" thru_hole circle
			(at 0 4.800092 180)
			(size 0.906272 0.906272)
			(drill 0.499872)
			(layers "*.Cu" "*.Mask")
			(remove_unused_layers no)
			(net "GND")
			(clearance 0.0508)
			(thermal_gap 0.0508)
		)
		(pad "E3" thru_hole circle
			(at 3.999992 4.800092 180)
			(size 0.906272 0.906272)
			(drill 0.499872)
			(layers "*.Cu" "*.Mask")
			(remove_unused_layers no)
			(net "GND")
			(clearance 0.0508)
			(thermal_gap 0.0508)
		)
		(pad "E5" thru_hole circle
			(at 7.999984 4.800092 180)
			(size 0.906272 0.906272)
			(drill 0.499872)
			(layers "*.Cu" "*.Mask")
			(remove_unused_layers no)
			(net "GND")
			(clearance 0.0508)
			(thermal_gap 0.0508)
		)
		(pad "E7" thru_hole circle
			(at 11.999976 4.800092 180)
			(size 0.906272 0.906272)
			(drill 0.499872)
			(layers "*.Cu" "*.Mask")
			(remove_unused_layers no)
			(net "GND")
			(clearance 0.0508)
			(thermal_gap 0.0508)
		)
		(pad "G2" thru_hole circle
			(at 1.999996 7.400036 180)
			(size 0.906272 0.906272)
			(drill 0.499872)
			(layers "*.Cu" "*.Mask")
			(remove_unused_layers no)
			(net "GND")
			(clearance 0.0508)
			(thermal_gap 0.0508)
		)
		(pad "G4" thru_hole circle
			(at 5.999988 7.400036 180)
			(size 0.906272 0.906272)
			(drill 0.499872)
			(layers "*.Cu" "*.Mask")
			(remove_unused_layers no)
			(net "GND")
			(clearance 0.0508)
			(thermal_gap 0.0508)
		)
		(pad "G6" thru_hole circle
			(at 9.99998 7.400036 180)
			(size 0.906272 0.906272)
			(drill 0.499872)
			(layers "*.Cu" "*.Mask")
			(remove_unused_layers no)
			(net "GND")
			(clearance 0.0508)
			(thermal_gap 0.0508)
		)
		(pad "G8" thru_hole circle
			(at 13.999972 7.400036 180)
			(size 0.906272 0.906272)
			(drill 0.499872)
			(layers "*.Cu" "*.Mask")
			(remove_unused_layers no)
			(net "GND")
			(clearance 0.0508)
			(thermal_gap 0.0508)
		)
		(pad "H1" thru_hole circle
			(at 0 8.400034 180)
			(size 0.906272 0.906272)
			(drill 0.499872)
			(layers "*.Cu" "*.Mask")
			(remove_unused_layers no)
			(net "GND")
			(clearance 0.0508)
			(thermal_gap 0.0508)
		)
		(pad "H3" thru_hole circle
			(at 3.999992 8.400034 180)
			(size 0.906272 0.906272)
			(drill 0.499872)
			(layers "*.Cu" "*.Mask")
			(remove_unused_layers no)
			(net "GND")
			(clearance 0.0508)
			(thermal_gap 0.0508)
		)
		(pad "H5" thru_hole circle
			(at 7.999984 8.400034 180)
			(size 0.906272 0.906272)
			(drill 0.499872)
			(layers "*.Cu" "*.Mask")
			(remove_unused_layers no)
			(net "GND")
			(clearance 0.0508)
			(thermal_gap 0.0508)
		)
		(pad "H7" thru_hole circle
			(at 11.999976 8.400034 180)
			(size 0.906272 0.906272)
			(drill 0.499872)
			(layers "*.Cu" "*.Mask")
			(remove_unused_layers no)
			(net "GND")
			(clearance 0.0508)
			(thermal_gap 0.0508)
		)
		(pad "J2" thru_hole circle
			(at 1.999996 10.999978 180)
			(size 0.906272 0.906272)
			(drill 0.499872)
			(layers "*.Cu" "*.Mask")
			(remove_unused_layers no)
			(net "GND")
			(clearance 0.0508)
			(thermal_gap 0.0508)
		)
		(pad "J4" thru_hole circle
			(at 5.999988 10.999978 180)
			(size 0.906272 0.906272)
			(drill 0.499872)
			(layers "*.Cu" "*.Mask")
			(remove_unused_layers no)
			(net "GND")
			(clearance 0.0508)
			(thermal_gap 0.0508)
		)
		(pad "J6" thru_hole circle
			(at 9.99998 10.999978 180)
			(size 0.906272 0.906272)
			(drill 0.499872)
			(layers "*.Cu" "*.Mask")
			(remove_unused_layers no)
			(net "GND")
			(clearance 0.0508)
			(thermal_gap 0.0508)
		)
	)
)
